(kicad_pcb
	(version 20241229)
	(generator "pcbnew")
	(generator_version "9.0")
	(general
		(thickness 1.63)
		(legacy_teardrops no)
	)
	(paper "A4")
	(title_block
		(title "CM4 Baseboard")
		(date "2026-01-05")
		(rev "1.1.1")
		(company "Antmicro Ltd")
		(comment 1 "www.antmicro.com")
		(comment 9 "footprints 475-478 of 506")
	)
	(layers
		(0 "F.Cu" signal)
		(4 "In1.Cu" power)
		(6 "In2.Cu" power)
		(8 "In3.Cu" signal)
		(10 "In4.Cu" signal)
		(2 "B.Cu" signal)
		(9 "F.Adhes" user "F.Adhesive")
		(11 "B.Adhes" user "B.Adhesive")
		(13 "F.Paste" user)
		(15 "B.Paste" user)
		(5 "F.SilkS" user "F.Silkscreen")
		(7 "B.SilkS" user "B.Silkscreen")
		(1 "F.Mask" user)
		(3 "B.Mask" user)
		(17 "Dwgs.User" user "User.Drawings")
		(19 "Cmts.User" user "User.Comments")
		(21 "Eco1.User" user "User.Eco1")
		(23 "Eco2.User" user "User.Eco2")
		(25 "Edge.Cuts" user)
		(27 "Margin" user)
		(31 "F.CrtYd" user "F.Courtyard")
		(29 "B.CrtYd" user "B.Courtyard")
		(35 "F.Fab" user)
		(33 "B.Fab" user)
	)
	(footprint "antmicro-footprints:R_Array_4x0402_Panasonic_EXB28V"
		(layer "B.Cu")
		(at 99.017962 172.5415 90)
		(property "Reference" "R705"
			(at 3.695 1.2 90)
			(layer "B.SilkS")
			(effects
				(font
					(size 0.7 0.7)
					(thickness 0.15)
				)
				(justify right bottom mirror)
			)
		)
		(property "Value" "R_4x100R_0402_array"
			(at -1.5 -2 90)
			(layer "B.Fab")
			(effects
				(font
					(size 0.7 0.7)
					(thickness 0.15)
				)
				(justify right bottom mirror)
			)
		)
		(property "Datasheet" "http://industrial.panasonic.com/cdbs/www-data/pdf/AOC0000/AOC0000C14.pdf"
			(at 0 0 90)
			(layer "B.Fab")
			(hide yes)
			(effects
				(font
					(size 1.27 1.27)
					(thickness 0.15)
				)
			)
		)
		(property "MPN" "EXB-28V101JX"
			(at 0 0 90)
			(unlocked yes)
			(layer "B.Fab")
			(hide yes)
			(effects
				(font
					(size 1 1)
					(thickness 0.15)
				)
				(justify mirror)
			)
		)
		(property "Manufacturer" "Panasonic"
			(at 0 0 90)
			(unlocked yes)
			(layer "B.Fab")
			(hide yes)
			(effects
				(font
					(size 1 1)
					(thickness 0.15)
				)
				(justify mirror)
			)
		)
		(property "Author" "Antmicro"
			(at 0 0 90)
			(unlocked yes)
			(layer "B.Fab")
			(hide yes)
			(effects
				(font
					(size 1 1)
					(thickness 0.15)
				)
				(justify mirror)
			)
		)
		(property "License" "Apache-2.0"
			(at 0 0 90)
			(unlocked yes)
			(layer "B.Fab")
			(hide yes)
			(effects
				(font
					(size 1 1)
					(thickness 0.15)
				)
				(justify mirror)
			)
		)
		(property "Val" "R_4x100R_0402"
			(at 0 0 90)
			(unlocked yes)
			(layer "B.Fab")
			(hide yes)
			(effects
				(font
					(size 1 1)
					(thickness 0.15)
				)
				(justify mirror)
			)
		)
		(sheetname "/Display/")
		(sheetfile "display.kicad_sch")
		(attr smd)
		(fp_line
			(start 1.25 -0.499)
			(end 1.25 0.499)
			(stroke
				(width 0.15)
				(type solid)
			)
			(layer "B.SilkS")
		)
		(fp_line
			(start -1.25 0.5)
			(end -1.25 -0.498)
			(stroke
				(width 0.15)
				(type solid)
			)
			(layer "B.SilkS")
		)
		(fp_rect
			(start -1.25 0.8)
			(end 1.25 -0.8)
			(stroke
				(width 0.05)
				(type solid)
			)
			(fill no)
			(layer "B.CrtYd")
		)
		(fp_line
			(start 0.998 -0.498)
			(end -1 -0.498)
			(stroke
				(width 0.15)
				(type solid)
			)
			(layer "B.Fab")
		)
		(fp_line
			(start -1 -0.498)
			(end -1 0.5)
			(stroke
				(width 0.15)
				(type solid)
			)
			(layer "B.Fab")
		)
		(fp_line
			(start 0.998 0.5)
			(end 0.998 -0.498)
			(stroke
				(width 0.15)
				(type solid)
			)
			(layer "B.Fab")
		)
		(fp_line
			(start -1 0.5)
			(end 0.998 0.5)
			(stroke
				(width 0.15)
				(type solid)
			)
			(layer "B.Fab")
		)
		(fp_text user "Author: Antmicro"
			(at -1.5 -4.5 270)
			(layer "B.Fab")
			(effects
				(font
					(size 0.7 0.7)
					(thickness 0.15)
				)
				(justify left bottom mirror)
			)
		)
		(fp_text user "License: Apache-2.0"
			(at -1.5 -5.75 270)
			(layer "B.Fab")
			(effects
				(font
					(size 0.7 0.7)
					(thickness 0.15)
				)
				(justify left bottom mirror)
			)
		)
		(fp_text user "${REFERENCE}"
			(at -1.5 -3.25 270)
			(layer "B.Fab")
			(effects
				(font
					(size 0.7 0.7)
					(thickness 0.15)
				)
				(justify left bottom mirror)
			)
		)
		(pad "1" smd roundrect
			(at -0.8875 -0.45 90)
			(size 0.525 0.5)
			(layers "B.Cu" "B.Mask" "B.Paste")
			(roundrect_rratio 0.25)
			(net 301 "Net-(R705-R1.1)")
			(pinfunction "R1.1")
			(pintype "passive")
		)
		(pad "2" smd roundrect
			(at -0.25 -0.45 90)
			(size 0.25 0.5)
			(layers "B.Cu" "B.Mask" "B.Paste")
			(roundrect_rratio 0.25)
			(net 302 "Net-(R705-R2.1)")
			(pinfunction "R2.1")
			(pintype "passive")
		)
		(pad "3" smd roundrect
			(at 0.25 -0.45 90)
			(size 0.25 0.5)
			(layers "B.Cu" "B.Mask" "B.Paste")
			(roundrect_rratio 0.25)
			(net 303 "Net-(R705-R3.1)")
			(pinfunction "R3.1")
			(pintype "passive")
		)
		(pad "4" smd roundrect
			(at 0.8875 -0.45 90)
			(size 0.525 0.5)
			(layers "B.Cu" "B.Mask" "B.Paste")
			(roundrect_rratio 0.25)
			(net 304 "Net-(R705-R4.1)")
			(pinfunction "R4.1")
			(pintype "passive")
		)
		(pad "5" smd roundrect
			(at 0.8875 0.45 90)
			(size 0.525 0.5)
			(layers "B.Cu" "B.Mask" "B.Paste")
			(roundrect_rratio 0.25)
			(net 121 "/Compute module/DSICtrl.~{IRQ2}")
			(pinfunction "R4.2")
			(pintype "passive")
		)
		(pad "6" smd roundrect
			(at 0.25 0.45 90)
			(size 0.25 0.5)
			(layers "B.Cu" "B.Mask" "B.Paste")
			(roundrect_rratio 0.25)
			(net 120 "/Compute module/DSICtrl.IRQ1")
			(pinfunction "R3.2")
			(pintype "passive")
		)
		(pad "7" smd roundrect
			(at -0.25 0.45 90)
			(size 0.25 0.5)
			(layers "B.Cu" "B.Mask" "B.Paste")
			(roundrect_rratio 0.25)
			(net 142 "/CSI/I_{2}C1.SCL")
			(pinfunction "R2.2")
			(pintype "passive")
		)
		(pad "8" smd roundrect
			(at -0.8875 0.45 90)
			(size 0.525 0.5)
			(layers "B.Cu" "B.Mask" "B.Paste")
			(roundrect_rratio 0.25)
			(net 143 "/CSI/I_{2}C1.SDA")
			(pinfunction "R1.2")
			(pintype "passive")
		)
	)
	(footprint "antmicro-footprints:C_0402_1005Metric"
		(layer "B.Cu")
		(at 60.417962 170.7565 -90)
		(descr "Capacitor SMD 0402")
		(tags "capacitor SMD 0402")
		(property "Reference" "C411"
			(at 1.33 -0.42 90)
			(layer "B.SilkS")
			(effects
				(font
					(size 0.7 0.7)
					(thickness 0.15)
				)
				(justify left bottom mirror)
			)
		)
		(property "Value" "C_100n_0402"
			(at -1.022927 -2.155213 90)
			(layer "B.Fab")
			(effects
				(font
					(size 0.7 0.7)
					(thickness 0.15)
				)
				(justify left bottom mirror)
			)
		)
		(property "Datasheet" "https://www.murata.com/products/productdetail?partno=GRM155R61H104KE14%23"
			(at 0 0 270)
			(layer "B.Fab")
			(hide yes)
			(effects
				(font
					(size 1.27 1.27)
					(thickness 0.15)
				)
			)
		)
		(property "MPN" "GRM155R61H104KE14D"
			(at 0 0 270)
			(unlocked yes)
			(layer "B.Fab")
			(hide yes)
			(effects
				(font
					(size 1 1)
					(thickness 0.15)
				)
				(justify mirror)
			)
		)
		(property "Manufacturer" "Murata"
			(at 0 0 270)
			(unlocked yes)
			(layer "B.Fab")
			(hide yes)
			(effects
				(font
					(size 1 1)
					(thickness 0.15)
				)
				(justify mirror)
			)
		)
		(property "Val" "100n"
			(at 0 0 270)
			(unlocked yes)
			(layer "B.Fab")
			(hide yes)
			(effects
				(font
					(size 1 1)
					(thickness 0.15)
				)
				(justify mirror)
			)
		)
		(property "License" "Apache-2.0"
			(at 0 0 270)
			(unlocked yes)
			(layer "B.Fab")
			(hide yes)
			(effects
				(font
					(size 1 1)
					(thickness 0.15)
				)
				(justify mirror)
			)
		)
		(property "Author" "Antmicro"
			(at 0 0 270)
			(unlocked yes)
			(layer "B.Fab")
			(hide yes)
			(effects
				(font
					(size 1 1)
					(thickness 0.15)
				)
				(justify mirror)
			)
		)
		(property "Voltage" "50V"
			(at 0 0 270)
			(unlocked yes)
			(layer "B.Fab")
			(hide yes)
			(effects
				(font
					(size 1 1)
					(thickness 0.15)
				)
				(justify mirror)
			)
		)
		(property "Dielectric" "X5R"
			(at 0 0 270)
			(unlocked yes)
			(layer "B.Fab")
			(hide yes)
			(effects
				(font
					(size 1 1)
					(thickness 0.15)
				)
				(justify mirror)
			)
		)
		(sheetname "/Ethernet/")
		(sheetfile "ethernet.kicad_sch")
		(attr smd)
		(fp_rect
			(start -0.925 0.47)
			(end 0.925 -0.47)
			(stroke
				(width 0.05)
				(type default)
			)
			(fill no)
			(layer "B.CrtYd")
		)
		(fp_line
			(start -0.494 0.25)
			(end 0.504 0.25)
			(stroke
				(width 0.15)
				(type solid)
			)
			(layer "B.Fab")
		)
		(fp_line
			(start 0.504 0.25)
			(end 0.504 -0.248)
			(stroke
				(width 0.15)
				(type solid)
			)
			(layer "B.Fab")
		)
		(fp_line
			(start -0.494 -0.248)
			(end -0.494 0.25)
			(stroke
				(width 0.15)
				(type solid)
			)
			(layer "B.Fab")
		)
		(fp_line
			(start 0.504 -0.248)
			(end -0.494 -0.248)
			(stroke
				(width 0.15)
				(type solid)
			)
			(layer "B.Fab")
		)
		(fp_text user "License: Apache-2.0"
			(at -0.939 -5.799 90)
			(layer "B.Fab")
			(effects
				(font
					(size 0.7 0.7)
					(thickness 0.15)
				)
				(justify left bottom mirror)
			)
		)
		(fp_text user "${REFERENCE}"
			(at -0.939 -4.599 90)
			(layer "B.Fab")
			(effects
				(font
					(size 0.7 0.7)
					(thickness 0.15)
				)
				(justify left bottom mirror)
			)
		)
		(fp_text user "Author: Antmicro"
			(at -0.939 -3.399 90)
			(layer "B.Fab")
			(effects
				(font
					(size 0.7 0.7)
					(thickness 0.15)
				)
				(justify left bottom mirror)
			)
		)
		(pad "1" smd roundrect
			(at -0.48 0 270)
			(size 0.59 0.64)
			(layers "B.Cu" "B.Mask" "B.Paste")
			(roundrect_rratio 0.25)
			(net 47 "/Ethernet/POE_12V")
			(pintype "passive")
		)
		(pad "2" smd roundrect
			(at 0.48 0 270)
			(size 0.59 0.64)
			(layers "B.Cu" "B.Mask" "B.Paste")
			(roundrect_rratio 0.25)
			(net 3 "GND")
			(pintype "passive")
		)
	)
	(footprint "antmicro-footprints:C_0402_1005Metric"
		(layer "B.Cu")
		(at 66.217962 177.1915 180)
		(descr "Capacitor SMD 0402")
		(tags "capacitor SMD 0402")
		(property "Reference" "C812"
			(at -3.782038 0.1915 0)
			(layer "B.SilkS")
			(effects
				(font
					(size 0.7 0.7)
					(thickness 0.15)
				)
				(justify left top mirror)
			)
		)
		(property "Value" "C_1n_0402"
			(at -1.022927 -2.155213 0)
			(layer "B.Fab")
			(effects
				(font
					(size 0.7 0.7)
					(thickness 0.15)
				)
				(justify left top mirror)
			)
		)
		(property "Datasheet" "https://www.murata.com/products/productdetail?partno=GRM1555C1H102JA01%23"
			(at 0 0 0)
			(layer "B.Fab")
			(hide yes)
			(effects
				(font
					(size 1.27 1.27)
					(thickness 0.15)
				)
			)
		)
		(property "Description" "SMD Multilayer Ceramic Capacitor, 1000 pF, 50 V, 0402 [1005 Metric], ± 5%, C0G / NP0, GRM Series"
			(at 0 0 0)
			(layer "B.Fab")
			(hide yes)
			(effects
				(font
					(size 1.27 1.27)
					(thickness 0.15)
				)
			)
		)
		(property "MPN" "GRM1555C1H102JA01D"
			(at 0 0 180)
			(unlocked yes)
			(layer "B.Fab")
			(hide yes)
			(effects
				(font
					(size 1 1)
					(thickness 0.15)
				)
				(justify mirror)
			)
		)
		(property "Manufacturer" "Murata"
			(at 0 0 180)
			(unlocked yes)
			(layer "B.Fab")
			(hide yes)
			(effects
				(font
					(size 1 1)
					(thickness 0.15)
				)
				(justify mirror)
			)
		)
		(property "License" "Apache-2.0"
			(at 0 0 180)
			(unlocked yes)
			(layer "B.Fab")
			(hide yes)
			(effects
				(font
					(size 1 1)
					(thickness 0.15)
				)
				(justify mirror)
			)
		)
		(property "Author" "Antmicro"
			(at 0 0 180)
			(unlocked yes)
			(layer "B.Fab")
			(hide yes)
			(effects
				(font
					(size 1 1)
					(thickness 0.15)
				)
				(justify mirror)
			)
		)
		(property "Val" "1n"
			(at 0 0 180)
			(unlocked yes)
			(layer "B.Fab")
			(hide yes)
			(effects
				(font
					(size 1 1)
					(thickness 0.15)
				)
				(justify mirror)
			)
		)
		(property "Voltage" "50V"
			(at 0 0 180)
			(unlocked yes)
			(layer "B.Fab")
			(hide yes)
			(effects
				(font
					(size 1 1)
					(thickness 0.15)
				)
				(justify mirror)
			)
		)
		(property "Dielectric" "C0G"
			(at 0 0 180)
			(unlocked yes)
			(layer "B.Fab")
			(hide yes)
			(effects
				(font
					(size 1 1)
					(thickness 0.15)
				)
				(justify mirror)
			)
		)
		(sheetname "/Peripherals/")
		(sheetfile "peripherals.kicad_sch")
		(attr smd)
		(fp_rect
			(start -0.925 0.47)
			(end 0.925 -0.47)
			(stroke
				(width 0.05)
				(type default)
			)
			(fill no)
			(layer "B.CrtYd")
		)
		(fp_line
			(start 0.504 0.25)
			(end 0.504 -0.248)
			(stroke
				(width 0.15)
				(type solid)
			)
			(layer "B.Fab")
		)
		(fp_line
			(start 0.504 -0.248)
			(end -0.494 -0.248)
			(stroke
				(width 0.15)
				(type solid)
			)
			(layer "B.Fab")
		)
		(fp_line
			(start -0.494 0.25)
			(end 0.504 0.25)
			(stroke
				(width 0.15)
				(type solid)
			)
			(layer "B.Fab")
		)
		(fp_line
			(start -0.494 -0.248)
			(end -0.494 0.25)
			(stroke
				(width 0.15)
				(type solid)
			)
			(layer "B.Fab")
		)
		(fp_text user "License: Apache-2.0"
			(at -0.939 -5.799 0)
			(layer "B.Fab")
			(effects
				(font
					(size 0.7 0.7)
					(thickness 0.15)
				)
				(justify left bottom mirror)
			)
		)
		(fp_text user "${REFERENCE}"
			(at -0.939 -4.599 0)
			(layer "B.Fab")
			(effects
				(font
					(size 0.7 0.7)
					(thickness 0.15)
				)
				(justify left bottom mirror)
			)
		)
		(fp_text user "Author: Antmicro"
			(at -0.939 -3.399 0)
			(layer "B.Fab")
			(effects
				(font
					(size 0.7 0.7)
					(thickness 0.15)
				)
				(justify left bottom mirror)
			)
		)
		(pad "1" smd roundrect
			(at -0.48 0 180)
			(size 0.59 0.64)
			(layers "B.Cu" "B.Mask" "B.Paste")
			(roundrect_rratio 0.25)
			(net 103 "Net-(U801-RXP)")
			(pintype "passive")
		)
		(pad "2" smd roundrect
			(at 0.48 0 180)
			(size 0.59 0.64)
			(layers "B.Cu" "B.Mask" "B.Paste")
			(roundrect_rratio 0.25)
			(net 102 "Net-(C812-Pad2)")
			(pintype "passive")
		)
	)
	(footprint "antmicro-footprints:R_0402_1005Metric"
		(layer "B.Cu")
		(at 129.267962 156.5415 180)
		(descr "Resistor SMD 0402")
		(tags "resistor SMD 0402")
		(property "Reference" "R512"
			(at -3.68 -0.245 0)
			(layer "B.SilkS")
			(effects
				(font
					(size 0.7 0.7)
					(thickness 0.15)
				)
				(justify left bottom mirror)
			)
		)
		(property "Value" "R_470R_0402"
			(at -1.011843 -1.772047 0)
			(layer "B.Fab")
			(effects
				(font
					(size 0.7 0.7)
					(thickness 0.15)
				)
				(justify left bottom mirror)
			)
		)
		(property "Datasheet" "https://www.bourns.com/docs/product-datasheets/cr.pdf"
			(at 0 0 180)
			(layer "B.Fab")
			(hide yes)
			(effects
				(font
					(size 1.27 1.27)
					(thickness 0.15)
				)
			)
		)
		(property "Manufacturer" "Bourns"
			(at 0 0 180)
			(unlocked yes)
			(layer "B.Fab")
			(hide yes)
			(effects
				(font
					(size 1 1)
					(thickness 0.15)
				)
				(justify mirror)
			)
		)
		(property "MPN" "CR0402-FX-4700GLF"
			(at 0 0 180)
			(unlocked yes)
			(layer "B.Fab")
			(hide yes)
			(effects
				(font
					(size 1 1)
					(thickness 0.15)
				)
				(justify mirror)
			)
		)
		(property "Val" "470R"
			(at 0 0 180)
			(unlocked yes)
			(layer "B.Fab")
			(hide yes)
			(effects
				(font
					(size 1 1)
					(thickness 0.15)
				)
				(justify mirror)
			)
		)
		(property "License" "Apache-2.0"
			(at 0 0 180)
			(unlocked yes)
			(layer "B.Fab")
			(hide yes)
			(effects
				(font
					(size 1 1)
					(thickness 0.15)
				)
				(justify mirror)
			)
		)
		(property "Author" "Antmicro"
			(at 0 0 180)
			(unlocked yes)
			(layer "B.Fab")
			(hide yes)
			(effects
				(font
					(size 1 1)
					(thickness 0.15)
				)
				(justify mirror)
			)
		)
		(property "Tolerance" "1%"
			(at 0 0 180)
			(unlocked yes)
			(layer "B.Fab")
			(hide yes)
			(effects
				(font
					(size 1 1)
					(thickness 0.15)
				)
				(justify mirror)
			)
		)
		(sheetname "/NVMe & microSD/")
		(sheetfile "nvme-micro-sd.kicad_sch")
		(attr smd)
		(fp_rect
			(start -0.925 0.47)
			(end 0.925 -0.47)
			(stroke
				(width 0.05)
				(type default)
			)
			(fill no)
			(layer "B.CrtYd")
		)
		(fp_rect
			(start -0.5 0.25)
			(end 0.5 -0.25)
			(stroke
				(width 0.15)
				(type solid)
			)
			(fill no)
			(layer "B.Fab")
		)
		(fp_text user "License: Apache-2.0"
			(at -0.95 -5.169 0)
			(layer "B.Fab")
			(effects
				(font
					(size 0.7 0.7)
					(thickness 0.15)
				)
				(justify left bottom mirror)
			)
		)
		(fp_text user "Author: Antmicro"
			(at -0.95 -4.169 0)
			(layer "B.Fab")
			(effects
				(font
					(size 0.7 0.7)
					(thickness 0.15)
				)
				(justify left bottom mirror)
			)
		)
		(fp_text user "${REFERENCE}"
			(at -0.95 -3.168 0)
			(layer "B.Fab")
			(effects
				(font
					(size 0.7 0.7)
					(thickness 0.15)
				)
				(justify left bottom mirror)
			)
		)
		(pad "1" smd roundrect
			(at -0.48 0 180)
			(size 0.59 0.64)
			(layers "B.Cu" "B.Mask" "B.Paste")
			(roundrect_rratio 0.25)
			(net 268 "Net-(J502-CD1)")
			(pintype "passive")
		)
		(pad "2" smd roundrect
			(at 0.48 0 180)
			(size 0.59 0.64)
			(layers "B.Cu" "B.Mask" "B.Paste")
			(roundrect_rratio 0.25)
			(net 9 "+3V3")
			(pintype "passive")
		)
	)
)
